(kicad_pcb
	(version 20260206)
	(generator "pcbnew")
	(generator_version "10.0")
	(general
		(thickness 1.6)
		(legacy_teardrops no)
	)
	(paper "A4")
	(title_block
		(title "04192023_DAF0TMB3IC0_F0TG_MB_C_brd_V02_OCP.brd")
		(comment 1 "Grand Teton / footprints 2950-2956 of 8354")
	)
	(layers
		(0 "F.Cu" signal "TOP")
		(4 "In1.Cu" signal "GND")
		(6 "In2.Cu" signal "IN1")
		(8 "In3.Cu" signal "GND1")
		(10 "In4.Cu" signal "IN2")
		(12 "In5.Cu" signal "GND2")
		(14 "In6.Cu" signal "IN3")
		(16 "In7.Cu" signal "GND3")
		(18 "In8.Cu" signal "VCC")
		(20 "In9.Cu" signal "VCC1")
		(22 "In10.Cu" signal "GND4")
		(24 "In11.Cu" signal "IN4")
		(26 "In12.Cu" signal "GND5")
		(28 "In13.Cu" signal "IN5")
		(30 "In14.Cu" signal "GND6")
		(32 "In15.Cu" signal "IN6")
		(34 "In16.Cu" signal "GND7")
		(2 "B.Cu" signal "BOTTOM")
		(9 "F.Adhes" user "F.Adhesive")
		(11 "B.Adhes" user "B.Adhesive")
		(13 "F.Paste" user "Package Geometry/Pastemask Top")
		(15 "B.Paste" user "Package Geometry/Pastemask Bottom")
		(5 "F.SilkS" user "Ref Des/Silkscreen Top")
		(7 "B.SilkS" user "Ref Des/Silkscreen Bottom")
		(1 "F.Mask" user "Board Geometry/Soldermask Top")
		(3 "B.Mask" user "Board Geometry/Soldermask Bottom")
		(17 "Dwgs.User" user "User.Drawings")
		(19 "Cmts.User" user "User.Comments")
		(21 "Eco1.User" user "User.Eco1")
		(23 "Eco2.User" user "User.Eco2")
		(25 "Edge.Cuts" user "Board Geometry/Outline")
		(27 "Margin" user)
		(31 "F.CrtYd" user "Package Geometry/Place Bound Top")
		(29 "B.CrtYd" user "Package Geometry/Place Bound Bottom")
		(35 "F.Fab" user "Ref Des/Assembly Top")
		(33 "B.Fab" user "Ref Des/Assembly Bottom")
	)
	(footprint ""
		(layer "F.Cu")
		(at 253.526036 -385.27736 90)
		(property "Reference" "PPQ5"
			(at -7.496048 -2.441956 0)
			(unlocked yes)
			(layer "F.SilkS")
			(effects
				(font
					(size 0.7874 0.5842)
					(thickness 0.1524)
				)
				(justify left)
			)
		)
		(property "Value" ""
			(at 0 0 90)
			(layer "F.Fab")
			(effects
				(font
					(size 1.27 1.27)
				)
			)
		)
		(duplicate_pad_numbers_are_jumpers no)
		(fp_line
			(start 2.350008 -2.649982)
			(end 2.350008 -2.4892)
			(stroke
				(width 0.1524)
				(type default)
			)
			(layer "F.SilkS")
		)
		(fp_line
			(start -2.350008 -2.649982)
			(end 2.350008 -2.649982)
			(stroke
				(width 0.1524)
				(type default)
			)
			(layer "F.SilkS")
		)
		(fp_line
			(start -2.350008 -2.4384)
			(end -2.350008 -2.649982)
			(stroke
				(width 0.1524)
				(type default)
			)
			(layer "F.SilkS")
		)
		(fp_line
			(start 2.350008 2.4892)
			(end 2.350008 2.649982)
			(stroke
				(width 0.1524)
				(type default)
			)
			(layer "F.SilkS")
		)
		(fp_line
			(start 2.350008 2.649982)
			(end -2.350008 2.649982)
			(stroke
				(width 0.1524)
				(type default)
			)
			(layer "F.SilkS")
		)
		(fp_line
			(start -2.350008 2.649982)
			(end -2.350008 2.413)
			(stroke
				(width 0.1524)
				(type default)
			)
			(layer "F.SilkS")
		)
		(fp_poly
			(pts
				(xy -3.438144 -3.488182) (xy -2.638044 -3.491738) (xy -3.052318 -2.44856)
			)
			(stroke
				(width 0)
				(type default)
			)
			(fill yes)
			(layer "F.SilkS")
		)
		(fp_line
			(start 2.350008 -2.649982)
			(end 2.350008 2.649982)
			(stroke
				(width 0.1)
				(type default)
			)
			(layer "F.Fab")
		)
		(fp_line
			(start -2.350008 -2.649982)
			(end 2.350008 -2.649982)
			(stroke
				(width 0.1)
				(type default)
			)
			(layer "F.Fab")
		)
		(fp_line
			(start 2.350008 2.649982)
			(end -2.350008 2.649982)
			(stroke
				(width 0.1)
				(type default)
			)
			(layer "F.Fab")
		)
		(fp_line
			(start -2.350008 2.649982)
			(end -2.350008 -2.649982)
			(stroke
				(width 0.1)
				(type default)
			)
			(layer "F.Fab")
		)
		(fp_poly
			(pts
				(xy -3.717544 -1.905) (xy -4.758944 -2.3241) (xy -4.758944 -1.524)
			)
			(stroke
				(width 0)
				(type default)
			)
			(fill yes)
			(layer "F.Fab")
		)
		(pad "1" smd rect
			(at -2.999994 -1.905)
			(size 0.7112 1.1684)
			(layers "F.Cu" "F.Mask" "F.Paste")
			(net "P12V_AUX")
		)
		(pad "2" smd rect
			(at -2.999994 -0.635)
			(size 0.7112 1.1684)
			(layers "F.Cu" "F.Mask" "F.Paste")
			(net "P12V_AUX")
		)
		(pad "3" smd rect
			(at -2.999994 0.635)
			(size 0.7112 1.1684)
			(layers "F.Cu" "F.Mask" "F.Paste")
			(net "P12V_AUX")
		)
		(pad "4" smd rect
			(at -2.999994 1.905)
			(size 0.7112 1.1684)
			(layers "F.Cu" "F.Mask" "F.Paste")
			(net "P12V_HSC_GATE_G1")
		)
		(pad "5" smd circle
			(at 0.925068 0)
			(size 0 0)
			(layers "F.Cu" "F.Mask" "F.Paste")
			(net "P12V_MAIN_R")
		)
		(zone
			(layer "F.Cu")
			(hatch none 0.5)
			(connect_pads
				(clearance 0)
			)
			(min_thickness 0.25)
			(keepout
				(tracks not_allowed)
				(vias allowed)
				(pads allowed)
				(copperpour not_allowed)
				(footprints allowed)
			)
			(placement
				(enabled no)
				(sheetname "")
			)
			(fill
				(thermal_gap 0.5)
				(thermal_bridge_width 0.5)
				(island_removal_mode 0)
			)
			(polygon
				(pts
					(xy 250.884436 -383.7178) (xy 256.167636 -383.7178) (xy 256.167636 -382.92786) (xy 250.884436 -382.92786)
				)
			)
		)
	)
	(footprint ""
		(layer "F.Cu")
		(at 420.75735 -37.277548)
		(property "Reference" "R6042"
			(at 0 0 0)
			(layer "F.SilkS")
			(hide yes)
			(effects
				(font
					(size 1.27 1.27)
				)
			)
		)
		(property "Value" ""
			(at 0 0 0)
			(layer "F.Fab")
			(effects
				(font
					(size 1.27 1.27)
				)
			)
		)
		(duplicate_pad_numbers_are_jumpers no)
		(fp_line
			(start -0.7874 -0.4064)
			(end 0.7874 -0.4064)
			(stroke
				(width 0.1524)
				(type default)
			)
			(layer "F.SilkS")
		)
		(fp_line
			(start -0.7874 0.4064)
			(end -0.7874 -0.4064)
			(stroke
				(width 0.1524)
				(type default)
			)
			(layer "F.SilkS")
		)
		(fp_line
			(start 0.7874 -0.4064)
			(end 0.7874 0.4064)
			(stroke
				(width 0.1524)
				(type default)
			)
			(layer "F.SilkS")
		)
		(fp_line
			(start 0.7874 0.4064)
			(end -0.7874 0.4064)
			(stroke
				(width 0.1524)
				(type default)
			)
			(layer "F.SilkS")
		)
		(fp_line
			(start -0.67945 -0.305054)
			(end -0.12065 -0.305054)
			(stroke
				(width 0.1)
				(type default)
			)
			(layer "F.Fab")
		)
		(fp_line
			(start -0.67945 0.3048)
			(end -0.67945 -0.305054)
			(stroke
				(width 0.1)
				(type default)
			)
			(layer "F.Fab")
		)
		(fp_line
			(start -0.12065 -0.305054)
			(end -0.12065 -0.2794)
			(stroke
				(width 0.1)
				(type default)
			)
			(layer "F.Fab")
		)
		(fp_line
			(start -0.12065 -0.2794)
			(end 0.12065 -0.2794)
			(stroke
				(width 0.1)
				(type default)
			)
			(layer "F.Fab")
		)
		(fp_line
			(start -0.12065 0.2794)
			(end -0.12065 0.3048)
			(stroke
				(width 0.1)
				(type default)
			)
			(layer "F.Fab")
		)
		(fp_line
			(start -0.12065 0.3048)
			(end -0.67945 0.3048)
			(stroke
				(width 0.1)
				(type default)
			)
			(layer "F.Fab")
		)
		(fp_line
			(start 0.120396 0.2794)
			(end -0.12065 0.2794)
			(stroke
				(width 0.1)
				(type default)
			)
			(layer "F.Fab")
		)
		(fp_line
			(start 0.120396 0.3048)
			(end 0.120396 0.2794)
			(stroke
				(width 0.1)
				(type default)
			)
			(layer "F.Fab")
		)
		(fp_line
			(start 0.12065 -0.3048)
			(end 0.67945 -0.3048)
			(stroke
				(width 0.1)
				(type default)
			)
			(layer "F.Fab")
		)
		(fp_line
			(start 0.12065 -0.2794)
			(end 0.12065 -0.3048)
			(stroke
				(width 0.1)
				(type default)
			)
			(layer "F.Fab")
		)
		(fp_line
			(start 0.67945 -0.3048)
			(end 0.67945 0.3048)
			(stroke
				(width 0.1)
				(type default)
			)
			(layer "F.Fab")
		)
		(fp_line
			(start 0.67945 0.3048)
			(end 0.120396 0.3048)
			(stroke
				(width 0.1)
				(type default)
			)
			(layer "F.Fab")
		)
		(pad "1" smd circle
			(at -0.40005 0)
			(size 0 0)
			(layers "F.Cu" "F.Mask" "F.Paste")
			(net "P3V3_AUX")
		)
		(pad "2" smd circle
			(at 0.40005 0)
			(size 0 0)
			(layers "F.Cu" "F.Mask" "F.Paste")
			(net "PU_FPGA_DEBUG_SW_SPARE")
		)
	)
	(footprint ""
		(layer "F.Cu")
		(at 340.162388 -165.803834 90)
		(property "Reference" "PL50"
			(at 0.439166 -4.093718 90)
			(unlocked yes)
			(layer "F.SilkS")
			(effects
				(font
					(size 0.7874 0.5842)
					(thickness 0.1524)
				)
				(justify left)
			)
		)
		(property "Value" ""
			(at 0 0 90)
			(layer "F.Fab")
			(effects
				(font
					(size 1.27 1.27)
				)
			)
		)
		(duplicate_pad_numbers_are_jumpers no)
		(fp_line
			(start 3.24993 -3.24993)
			(end 3.24993 -2.2352)
			(stroke
				(width 0.1524)
				(type default)
			)
			(layer "F.SilkS")
		)
		(fp_line
			(start -3.24993 -3.24993)
			(end 3.24993 -3.24993)
			(stroke
				(width 0.1524)
				(type default)
			)
			(layer "F.SilkS")
		)
		(fp_line
			(start -3.24993 -2.2352)
			(end -3.24993 -3.24993)
			(stroke
				(width 0.1524)
				(type default)
			)
			(layer "F.SilkS")
		)
		(fp_line
			(start 3.24993 2.2352)
			(end 3.24993 3.24993)
			(stroke
				(width 0.1524)
				(type default)
			)
			(layer "F.SilkS")
		)
		(fp_line
			(start 3.24993 3.24993)
			(end -3.24993 3.24993)
			(stroke
				(width 0.1524)
				(type default)
			)
			(layer "F.SilkS")
		)
		(fp_line
			(start -3.24993 3.24993)
			(end -3.24993 2.2352)
			(stroke
				(width 0.1524)
				(type default)
			)
			(layer "F.SilkS")
		)
		(fp_line
			(start 3.24993 -3.24993)
			(end 3.24993 3.24993)
			(stroke
				(width 0.1)
				(type default)
			)
			(layer "F.Fab")
		)
		(fp_line
			(start -3.24993 -3.24993)
			(end 3.24993 -3.24993)
			(stroke
				(width 0.1)
				(type default)
			)
			(layer "F.Fab")
		)
		(fp_line
			(start 3.24993 3.24993)
			(end -3.24993 3.24993)
			(stroke
				(width 0.1)
				(type default)
			)
			(layer "F.Fab")
		)
		(fp_line
			(start -3.24993 3.24993)
			(end -3.24993 -3.24993)
			(stroke
				(width 0.1)
				(type default)
			)
			(layer "F.Fab")
		)
		(pad "1" smd rect
			(at -2.29997 0 90)
			(size 2.0066 4.2164)
			(layers "F.Cu" "F.Mask" "F.Paste")
			(net "GND")
		)
		(pad "2" smd rect
			(at 2.29997 0 90)
			(size 2.0066 4.2164)
			(layers "F.Cu" "F.Mask" "F.Paste")
			(net "IND_CPU0_P0_CPL0")
		)
	)
	(footprint ""
		(layer "F.Cu")
		(at 189.865 -100.294948 90)
		(property "Reference" "R184"
			(at 0 0 90)
			(layer "F.SilkS")
			(hide yes)
			(effects
				(font
					(size 1.27 1.27)
				)
			)
		)
		(property "Value" ""
			(at 0 0 90)
			(layer "F.Fab")
			(effects
				(font
					(size 1.27 1.27)
				)
			)
		)
		(duplicate_pad_numbers_are_jumpers no)
		(fp_line
			(start 0.7874 -0.4064)
			(end 0.7874 0.4064)
			(stroke
				(width 0.1524)
				(type default)
			)
			(layer "F.SilkS")
		)
		(fp_line
			(start -0.7874 -0.4064)
			(end 0.7874 -0.4064)
			(stroke
				(width 0.1524)
				(type default)
			)
			(layer "F.SilkS")
		)
		(fp_line
			(start 0.7874 0.4064)
			(end -0.7874 0.4064)
			(stroke
				(width 0.1524)
				(type default)
			)
			(layer "F.SilkS")
		)
		(fp_line
			(start -0.7874 0.4064)
			(end -0.7874 -0.4064)
			(stroke
				(width 0.1524)
				(type default)
			)
			(layer "F.SilkS")
		)
		(fp_line
			(start -0.12065 -0.305054)
			(end -0.12065 -0.2794)
			(stroke
				(width 0.1)
				(type default)
			)
			(layer "F.Fab")
		)
		(fp_line
			(start -0.67945 -0.305054)
			(end -0.12065 -0.305054)
			(stroke
				(width 0.1)
				(type default)
			)
			(layer "F.Fab")
		)
		(fp_line
			(start 0.67945 -0.3048)
			(end 0.67945 0.3048)
			(stroke
				(width 0.1)
				(type default)
			)
			(layer "F.Fab")
		)
		(fp_line
			(start 0.12065 -0.3048)
			(end 0.67945 -0.3048)
			(stroke
				(width 0.1)
				(type default)
			)
			(layer "F.Fab")
		)
		(fp_line
			(start 0.12065 -0.2794)
			(end 0.12065 -0.3048)
			(stroke
				(width 0.1)
				(type default)
			)
			(layer "F.Fab")
		)
		(fp_line
			(start -0.12065 -0.2794)
			(end 0.12065 -0.2794)
			(stroke
				(width 0.1)
				(type default)
			)
			(layer "F.Fab")
		)
		(fp_line
			(start 0.120396 0.2794)
			(end -0.12065 0.2794)
			(stroke
				(width 0.1)
				(type default)
			)
			(layer "F.Fab")
		)
		(fp_line
			(start -0.12065 0.2794)
			(end -0.12065 0.3048)
			(stroke
				(width 0.1)
				(type default)
			)
			(layer "F.Fab")
		)
		(fp_line
			(start 0.67945 0.3048)
			(end 0.120396 0.3048)
			(stroke
				(width 0.1)
				(type default)
			)
			(layer "F.Fab")
		)
		(fp_line
			(start 0.120396 0.3048)
			(end 0.120396 0.2794)
			(stroke
				(width 0.1)
				(type default)
			)
			(layer "F.Fab")
		)
		(fp_line
			(start -0.12065 0.3048)
			(end -0.67945 0.3048)
			(stroke
				(width 0.1)
				(type default)
			)
			(layer "F.Fab")
		)
		(fp_line
			(start -0.67945 0.3048)
			(end -0.67945 -0.305054)
			(stroke
				(width 0.1)
				(type default)
			)
			(layer "F.Fab")
		)
		(pad "1" smd circle
			(at -0.40005 0 90)
			(size 0 0)
			(layers "F.Cu" "F.Mask" "F.Paste")
			(net "CPU0_CORETYPE1")
		)
		(pad "2" smd circle
			(at 0.40005 0 90)
			(size 0 0)
			(layers "F.Cu" "F.Mask" "F.Paste")
			(net "FM_CPU0_CORETYPE1")
		)
	)
	(footprint ""
		(layer "F.Cu")
		(at 76.115164 -18.066512)
		(property "Reference" "PR3805"
			(at 0 0 0)
			(layer "F.SilkS")
			(hide yes)
			(effects
				(font
					(size 1.27 1.27)
				)
			)
		)
		(property "Value" ""
			(at 0 0 0)
			(layer "F.Fab")
			(effects
				(font
					(size 1.27 1.27)
				)
			)
		)
		(duplicate_pad_numbers_are_jumpers no)
		(fp_line
			(start -0.7874 -0.4064)
			(end 0.7874 -0.4064)
			(stroke
				(width 0.1524)
				(type default)
			)
			(layer "F.SilkS")
		)
		(fp_line
			(start -0.7874 0.4064)
			(end -0.7874 -0.4064)
			(stroke
				(width 0.1524)
				(type default)
			)
			(layer "F.SilkS")
		)
		(fp_line
			(start 0.7874 -0.4064)
			(end 0.7874 0.4064)
			(stroke
				(width 0.1524)
				(type default)
			)
			(layer "F.SilkS")
		)
		(fp_line
			(start 0.7874 0.4064)
			(end -0.7874 0.4064)
			(stroke
				(width 0.1524)
				(type default)
			)
			(layer "F.SilkS")
		)
		(fp_line
			(start -0.67945 -0.305054)
			(end -0.12065 -0.305054)
			(stroke
				(width 0.1)
				(type default)
			)
			(layer "F.Fab")
		)
		(fp_line
			(start -0.67945 0.3048)
			(end -0.67945 -0.305054)
			(stroke
				(width 0.1)
				(type default)
			)
			(layer "F.Fab")
		)
		(fp_line
			(start -0.12065 -0.305054)
			(end -0.12065 -0.2794)
			(stroke
				(width 0.1)
				(type default)
			)
			(layer "F.Fab")
		)
		(fp_line
			(start -0.12065 -0.2794)
			(end 0.12065 -0.2794)
			(stroke
				(width 0.1)
				(type default)
			)
			(layer "F.Fab")
		)
		(fp_line
			(start -0.12065 0.2794)
			(end -0.12065 0.3048)
			(stroke
				(width 0.1)
				(type default)
			)
			(layer "F.Fab")
		)
		(fp_line
			(start -0.12065 0.3048)
			(end -0.67945 0.3048)
			(stroke
				(width 0.1)
				(type default)
			)
			(layer "F.Fab")
		)
		(fp_line
			(start 0.120396 0.2794)
			(end -0.12065 0.2794)
			(stroke
				(width 0.1)
				(type default)
			)
			(layer "F.Fab")
		)
		(fp_line
			(start 0.120396 0.3048)
			(end 0.120396 0.2794)
			(stroke
				(width 0.1)
				(type default)
			)
			(layer "F.Fab")
		)
		(fp_line
			(start 0.12065 -0.3048)
			(end 0.67945 -0.3048)
			(stroke
				(width 0.1)
				(type default)
			)
			(layer "F.Fab")
		)
		(fp_line
			(start 0.12065 -0.2794)
			(end 0.12065 -0.3048)
			(stroke
				(width 0.1)
				(type default)
			)
			(layer "F.Fab")
		)
		(fp_line
			(start 0.67945 -0.3048)
			(end 0.67945 0.3048)
			(stroke
				(width 0.1)
				(type default)
			)
			(layer "F.Fab")
		)
		(fp_line
			(start 0.67945 0.3048)
			(end 0.120396 0.3048)
			(stroke
				(width 0.1)
				(type default)
			)
			(layer "F.Fab")
		)
		(pad "1" smd circle
			(at -0.40005 0)
			(size 0 0)
			(layers "F.Cu" "F.Mask" "F.Paste")
			(net "P12V_AUX")
		)
		(pad "2" smd circle
			(at 0.40005 0)
			(size 0 0)
			(layers "F.Cu" "F.Mask" "F.Paste")
			(net "P12V_OCP_UV_2")
		)
	)
	(footprint ""
		(layer "F.Cu")
		(at 374.846342 -416.899344 -90)
		(property "Reference" "C6567"
			(at 0 0 270)
			(layer "F.SilkS")
			(hide yes)
			(effects
				(font
					(size 1.27 1.27)
				)
			)
		)
		(property "Value" ""
			(at 0 0 270)
			(layer "F.Fab")
			(effects
				(font
					(size 1.27 1.27)
				)
			)
		)
		(duplicate_pad_numbers_are_jumpers no)
		(fp_line
			(start -0.299974 0.150114)
			(end -0.299974 -0.150114)
			(stroke
				(width 0.1)
				(type default)
			)
			(layer "F.Fab")
		)
		(fp_line
			(start 0.299974 0.150114)
			(end -0.299974 0.150114)
			(stroke
				(width 0.1)
				(type default)
			)
			(layer "F.Fab")
		)
		(fp_line
			(start -0.299974 -0.150114)
			(end 0.299974 -0.150114)
			(stroke
				(width 0.1)
				(type default)
			)
			(layer "F.Fab")
		)
		(fp_line
			(start 0.299974 -0.150114)
			(end 0.299974 0.150114)
			(stroke
				(width 0.1)
				(type default)
			)
			(layer "F.Fab")
		)
		(pad "1" smd rect
			(at -0.2667 0 270)
			(size 0.3048 0.381)
			(layers "F.Cu" "F.Mask" "F.Paste")
			(net "P5E_CPU0_P2_TX_BUF_C_DP<1>")
		)
		(pad "2" smd rect
			(at 0.2667 0 270)
			(size 0.3048 0.381)
			(layers "F.Cu" "F.Mask" "F.Paste")
			(net "P5E_CPU0_P2_TX_BUF_DP<1>")
		)
	)
	(footprint ""
		(layer "F.Cu")
		(at 210.608672 -126.469648)
		(property "Reference" "C10"
			(at 0 0 0)
			(layer "F.SilkS")
			(hide yes)
			(effects
				(font
					(size 1.27 1.27)
				)
			)
		)
		(property "Value" ""
			(at 0 0 0)
			(layer "F.Fab")
			(effects
				(font
					(size 1.27 1.27)
				)
			)
		)
		(duplicate_pad_numbers_are_jumpers no)
		(fp_line
			(start -0.7874 -0.4064)
			(end 0.7874 -0.4064)
			(stroke
				(width 0.1524)
				(type default)
			)
			(layer "F.SilkS")
		)
		(fp_line
			(start -0.7874 0.4064)
			(end -0.7874 -0.4064)
			(stroke
				(width 0.1524)
				(type default)
			)
			(layer "F.SilkS")
		)
		(fp_line
			(start 0.7874 -0.4064)
			(end 0.7874 0.4064)
			(stroke
				(width 0.1524)
				(type default)
			)
			(layer "F.SilkS")
		)
		(fp_line
			(start 0.7874 0.4064)
			(end -0.7874 0.4064)
			(stroke
				(width 0.1524)
				(type default)
			)
			(layer "F.SilkS")
		)
		(fp_line
			(start -0.67945 -0.305054)
			(end -0.12065 -0.305054)
			(stroke
				(width 0.1)
				(type default)
			)
			(layer "F.Fab")
		)
		(fp_line
			(start -0.67945 0.3048)
			(end -0.67945 -0.305054)
			(stroke
				(width 0.1)
				(type default)
			)
			(layer "F.Fab")
		)
		(fp_line
			(start -0.12065 -0.305054)
			(end -0.12065 -0.2794)
			(stroke
				(width 0.1)
				(type default)
			)
			(layer "F.Fab")
		)
		(fp_line
			(start -0.12065 -0.2794)
			(end 0.12065 -0.2794)
			(stroke
				(width 0.1)
				(type default)
			)
			(layer "F.Fab")
		)
		(fp_line
			(start -0.12065 0.2794)
			(end -0.12065 0.3048)
			(stroke
				(width 0.1)
				(type default)
			)
			(layer "F.Fab")
		)
		(fp_line
			(start -0.12065 0.3048)
			(end -0.67945 0.3048)
			(stroke
				(width 0.1)
				(type default)
			)
			(layer "F.Fab")
		)
		(fp_line
			(start 0.120396 0.2794)
			(end -0.12065 0.2794)
			(stroke
				(width 0.1)
				(type default)
			)
			(layer "F.Fab")
		)
		(fp_line
			(start 0.120396 0.3048)
			(end 0.120396 0.2794)
			(stroke
				(width 0.1)
				(type default)
			)
			(layer "F.Fab")
		)
		(fp_line
			(start 0.12065 -0.3048)
			(end 0.67945 -0.3048)
			(stroke
				(width 0.1)
				(type default)
			)
			(layer "F.Fab")
		)
		(fp_line
			(start 0.12065 -0.2794)
			(end 0.12065 -0.3048)
			(stroke
				(width 0.1)
				(type default)
			)
			(layer "F.Fab")
		)
		(fp_line
			(start 0.67945 -0.3048)
			(end 0.67945 0.3048)
			(stroke
				(width 0.1)
				(type default)
			)
			(layer "F.Fab")
		)
		(fp_line
			(start 0.67945 0.3048)
			(end 0.120396 0.3048)
			(stroke
				(width 0.1)
				(type default)
			)
			(layer "F.Fab")
		)
		(pad "1" smd circle
			(at -0.40005 0)
			(size 0 0)
			(layers "F.Cu" "F.Mask" "F.Paste")
			(net "P3V3_AUX")
		)
		(pad "2" smd circle
			(at 0.40005 0)
			(size 0 0)
			(layers "F.Cu" "F.Mask" "F.Paste")
			(net "GND")
		)
	)
)
